(kicad_pcb
	(version 20260206)
	(generator "pcbnew")
	(generator_version "10.0")
	(general
		(thickness 1.6)
		(legacy_teardrops no)
	)
	(paper "A4")
	(title_block
		(title "Bryce Canyon_F.DPB_16315-1-OCP.brd")
		(comment 1 "Bryce Canyon / footprints 788-794 of 2223")
	)
	(layers
		(0 "F.Cu" signal "TOP")
		(4 "In1.Cu" signal "L2GND")
		(6 "In2.Cu" signal "L3")
		(8 "In3.Cu" signal "L4GND")
		(10 "In4.Cu" signal "L5")
		(12 "In5.Cu" signal "L6VCC")
		(14 "In6.Cu" signal "L7VCC")
		(16 "In7.Cu" signal "L8")
		(18 "In8.Cu" signal "L9GND")
		(20 "In9.Cu" signal "L10")
		(22 "In10.Cu" signal "L11GND")
		(2 "B.Cu" signal "BOTTOM")
		(9 "F.Adhes" user "F.Adhesive")
		(11 "B.Adhes" user "B.Adhesive")
		(13 "F.Paste" user "Package Geometry/Pastemask Top")
		(15 "B.Paste" user "Package Geometry/Pastemask Bottom")
		(5 "F.SilkS" user "Ref Des/Silkscreen Top")
		(7 "B.SilkS" user "Ref Des/Silkscreen Bottom")
		(1 "F.Mask" user "Board Geometry/Soldermask Top")
		(3 "B.Mask" user "Board Geometry/Soldermask Bottom")
		(17 "Dwgs.User" user "User.Drawings")
		(19 "Cmts.User" user "User.Comments")
		(21 "Eco1.User" user "User.Eco1")
		(23 "Eco2.User" user "User.Eco2")
		(25 "Edge.Cuts" user "Board Geometry/Outline")
		(27 "Margin" user)
		(31 "F.CrtYd" user "Package Geometry/Place Bound Top")
		(29 "B.CrtYd" user "Package Geometry/Place Bound Bottom")
		(35 "F.Fab" user "Ref Des/Assembly Top")
		(33 "B.Fab" user "Ref Des/Assembly Bottom")
	)
	(footprint ""
		(layer "F.Cu")
		(at 345.842844 -288.39287)
		(property "Reference" "Q294"
			(at 0 0 0)
			(layer "F.SilkS")
			(hide yes)
			(effects
				(font
					(size 1.27 1.27)
				)
			)
		)
		(property "Value" "SSM3K324R-GP"
			(at 0.127 -8.9662 0)
			(unlocked yes)
			(layer "F.Fab")
			(hide yes)
			(effects
				(font
					(size 1.016 1.016)
					(thickness 0.1524)
				)
			)
		)
		(property "Device Type" "SOT23DGS2D4H35"
			(at 0.127 -10.4902 0)
			(unlocked yes)
			(layer "F.Fab")
			(hide yes)
			(effects
				(font
					(size 1.016 1.016)
					(thickness 0.1524)
				)
			)
		)
		(duplicate_pad_numbers_are_jumpers no)
		(fp_line
			(start -1.651 -1.778)
			(end -1.651 1.778)
			(stroke
				(width 0.1524)
				(type default)
			)
			(layer "F.SilkS")
		)
		(fp_line
			(start -1.651 1.778)
			(end 1.651 1.778)
			(stroke
				(width 0.1524)
				(type default)
			)
			(layer "F.SilkS")
		)
		(fp_line
			(start 1.651 -1.778)
			(end -1.651 -1.778)
			(stroke
				(width 0.1524)
				(type default)
			)
			(layer "F.SilkS")
		)
		(fp_line
			(start 1.651 1.778)
			(end 1.651 -1.778)
			(stroke
				(width 0.1524)
				(type default)
			)
			(layer "F.SilkS")
		)
		(fp_poly
			(pts
				(xy -1.778 1.8796) (xy -1.778 -1.8796) (xy 1.778 -1.8796) (xy 1.778 1.8796)
			)
			(stroke
				(width 0)
				(type default)
			)
			(fill no)
			(layer "F.CrtYd")
		)
		(fp_poly
			(pts
				(xy -1.778 1.8796) (xy -1.778 -1.8796) (xy 1.778 -1.8796) (xy 1.778 1.8796)
			)
			(stroke
				(width 0)
				(type default)
			)
			(fill no)
			(layer "F.Fab")
		)
		(pad "D" smd custom
			(at 0 -0.9525)
			(size 0.1905 0.1905)
			(layers "F.Cu" "F.Mask" "F.Paste")
			(net "DRV_ACT_31_N")
			(options
				(clearance outline)
				(anchor circle)
			)
			(primitives
				(gr_poly
					(pts
						(arc
							(start -0.1778 0.5715)
							(mid -0.321484 0.511984)
							(end -0.381 0.3683)
						)
						(arc
							(start -0.381 -0.3683)
							(mid -0.321484 -0.511984)
							(end -0.1778 -0.5715)
						)
						(arc
							(start 0.1778 -0.5715)
							(mid 0.321484 -0.511984)
							(end 0.381 -0.3683)
						)
						(arc
							(start 0.381 0.3683)
							(mid 0.321484 0.511984)
							(end 0.1778 0.5715)
						)
					)
					(width 0)
					(fill yes)
				)
			)
		)
		(pad "G" smd custom
			(at -0.98425 0.9525)
			(size 0.1905 0.1905)
			(layers "F.Cu" "F.Mask" "F.Paste")
			(net "DRIVE_B_31_ACT")
			(options
				(clearance outline)
				(anchor circle)
			)
			(primitives
				(gr_poly
					(pts
						(arc
							(start -0.1778 0.5715)
							(mid -0.321484 0.511984)
							(end -0.381 0.3683)
						)
						(arc
							(start -0.381 -0.3683)
							(mid -0.321484 -0.511984)
							(end -0.1778 -0.5715)
						)
						(arc
							(start 0.1778 -0.5715)
							(mid 0.321484 -0.511984)
							(end 0.381 -0.3683)
						)
						(arc
							(start 0.381 0.3683)
							(mid 0.321484 0.511984)
							(end 0.1778 0.5715)
						)
					)
					(width 0)
					(fill yes)
				)
			)
		)
		(pad "S" smd custom
			(at 0.98425 0.9525)
			(size 0.1905 0.1905)
			(layers "F.Cu" "F.Mask" "F.Paste")
			(net "GND")
			(options
				(clearance outline)
				(anchor circle)
			)
			(primitives
				(gr_poly
					(pts
						(arc
							(start -0.1778 0.5715)
							(mid -0.321484 0.511984)
							(end -0.381 0.3683)
						)
						(arc
							(start -0.381 -0.3683)
							(mid -0.321484 -0.511984)
							(end -0.1778 -0.5715)
						)
						(arc
							(start 0.1778 -0.5715)
							(mid 0.321484 -0.511984)
							(end 0.381 -0.3683)
						)
						(arc
							(start 0.381 0.3683)
							(mid 0.321484 0.511984)
							(end 0.1778 0.5715)
						)
					)
					(width 0)
					(fill yes)
				)
			)
		)
	)
	(footprint ""
		(layer "F.Cu")
		(at 98.897948 -177.169318 -90)
		(property "Reference" "R452"
			(at 0 0 270)
			(layer "F.SilkS")
			(hide yes)
			(effects
				(font
					(size 1.27 1.27)
				)
			)
		)
		(property "Value" "10KR2F-2-GP"
			(at 0.064008 -3.993896 270)
			(unlocked yes)
			(layer "F.Fab")
			(hide yes)
			(effects
				(font
					(size 1.016 1.016)
					(thickness 0.1524)
				)
			)
		)
		(property "Device Type" "R402H16"
			(at 0.064008 -5.517896 270)
			(unlocked yes)
			(layer "F.Fab")
			(hide yes)
			(effects
				(font
					(size 1.016 1.016)
					(thickness 0.1524)
				)
			)
		)
		(duplicate_pad_numbers_are_jumpers no)
		(fp_line
			(start -0.508 -0.9398)
			(end -0.508 0.9398)
			(stroke
				(width 0.1524)
				(type default)
			)
			(layer "F.SilkS")
		)
		(fp_line
			(start 0.508 -0.9398)
			(end -0.508 -0.9398)
			(stroke
				(width 0.1524)
				(type default)
			)
			(layer "F.SilkS")
		)
		(fp_rect
			(start -0.508 0.9398)
			(end 0.508 -0.9398)
			(stroke
				(width 0)
				(type default)
			)
			(fill no)
			(layer "F.CrtYd")
		)
		(fp_rect
			(start -0.508 0.9398)
			(end 0.508 -0.9398)
			(stroke
				(width 0)
				(type default)
			)
			(fill no)
			(layer "F.Fab")
		)
		(pad "1" smd custom
			(at 0 -0.4445 270)
			(size 0.1397 0.1397)
			(layers "F.Cu" "F.Mask" "F.Paste")
			(net "P3V3_STBY_A")
			(options
				(clearance outline)
				(anchor circle)
			)
			(primitives
				(gr_poly
					(pts
						(arc
							(start -0.1778 -0.2794)
							(mid -0.249642 -0.249642)
							(end -0.2794 -0.1778)
						)
						(arc
							(start -0.2794 0.1778)
							(mid -0.249642 0.249642)
							(end -0.1778 0.2794)
						)
						(arc
							(start 0.1778 0.2794)
							(mid 0.249642 0.249642)
							(end 0.2794 0.1778)
						)
						(arc
							(start 0.2794 -0.1778)
							(mid 0.249642 -0.249642)
							(end 0.1778 -0.2794)
						)
					)
					(width 0)
					(fill yes)
				)
			)
		)
		(pad "2" smd custom
			(at 0 0.4445 270)
			(size 0.1397 0.1397)
			(layers "F.Cu" "F.Mask" "F.Paste")
			(net "HDD_PRSNT_14")
			(options
				(clearance outline)
				(anchor circle)
			)
			(primitives
				(gr_poly
					(pts
						(arc
							(start -0.1778 -0.2794)
							(mid -0.249642 -0.249642)
							(end -0.2794 -0.1778)
						)
						(arc
							(start -0.2794 0.1778)
							(mid -0.249642 0.249642)
							(end -0.1778 0.2794)
						)
						(arc
							(start 0.1778 0.2794)
							(mid 0.249642 0.249642)
							(end 0.2794 0.1778)
						)
						(arc
							(start 0.2794 -0.1778)
							(mid 0.249642 -0.249642)
							(end 0.1778 -0.2794)
						)
					)
					(width 0)
					(fill yes)
				)
			)
		)
	)
	(footprint ""
		(layer "F.Cu")
		(at 427.898052 -272.585942 180)
		(property "Reference" "R345"
			(at 0 0 180)
			(layer "F.SilkS")
			(hide yes)
			(effects
				(font
					(size 1.27 1.27)
				)
			)
		)
		(property "Value" "1KR2F-3-GP"
			(at 0.064008 -3.993896 180)
			(unlocked yes)
			(layer "F.Fab")
			(hide yes)
			(effects
				(font
					(size 1.016 1.016)
					(thickness 0.1524)
				)
			)
		)
		(property "Device Type" "R402H16"
			(at 0.064008 -5.517896 180)
			(unlocked yes)
			(layer "F.Fab")
			(hide yes)
			(effects
				(font
					(size 1.016 1.016)
					(thickness 0.1524)
				)
			)
		)
		(duplicate_pad_numbers_are_jumpers no)
		(fp_line
			(start 0.508 -0.9398)
			(end -0.508 -0.9398)
			(stroke
				(width 0.1524)
				(type default)
			)
			(layer "F.SilkS")
		)
		(fp_line
			(start -0.508 -0.9398)
			(end -0.508 0.9398)
			(stroke
				(width 0.1524)
				(type default)
			)
			(layer "F.SilkS")
		)
		(fp_rect
			(start -0.508 0.9398)
			(end 0.508 -0.9398)
			(stroke
				(width 0)
				(type default)
			)
			(fill no)
			(layer "F.CrtYd")
		)
		(fp_rect
			(start -0.508 0.9398)
			(end 0.508 -0.9398)
			(stroke
				(width 0)
				(type default)
			)
			(fill no)
			(layer "F.Fab")
		)
		(pad "1" smd custom
			(at 0 -0.4445 180)
			(size 0.1397 0.1397)
			(layers "F.Cu" "F.Mask" "F.Paste")
			(net "P3V3_STBY_A")
			(options
				(clearance outline)
				(anchor circle)
			)
			(primitives
				(gr_poly
					(pts
						(arc
							(start -0.1778 -0.2794)
							(mid -0.249642 -0.249642)
							(end -0.2794 -0.1778)
						)
						(arc
							(start -0.2794 0.1778)
							(mid -0.249642 0.249642)
							(end -0.1778 0.2794)
						)
						(arc
							(start 0.1778 0.2794)
							(mid 0.249642 0.249642)
							(end 0.2794 0.1778)
						)
						(arc
							(start 0.2794 -0.1778)
							(mid 0.249642 -0.249642)
							(end 0.1778 -0.2794)
						)
					)
					(width 0)
					(fill yes)
				)
			)
		)
		(pad "2" smd custom
			(at 0 0.4445 180)
			(size 0.1397 0.1397)
			(layers "F.Cu" "F.Mask" "F.Paste")
			(net "SW_PWR_R_HDD9")
			(options
				(clearance outline)
				(anchor circle)
			)
			(primitives
				(gr_poly
					(pts
						(arc
							(start -0.1778 -0.2794)
							(mid -0.249642 -0.249642)
							(end -0.2794 -0.1778)
						)
						(arc
							(start -0.2794 0.1778)
							(mid -0.249642 0.249642)
							(end -0.1778 0.2794)
						)
						(arc
							(start 0.1778 0.2794)
							(mid 0.249642 0.249642)
							(end 0.2794 0.1778)
						)
						(arc
							(start 0.2794 -0.1778)
							(mid 0.249642 -0.249642)
							(end 0.1778 -0.2794)
						)
					)
					(width 0)
					(fill yes)
				)
			)
		)
	)
	(footprint ""
		(layer "F.Cu")
		(at 338.829904 -130.378962 -90)
		(property "Reference" "R530"
			(at 0 0 270)
			(layer "F.SilkS")
			(hide yes)
			(effects
				(font
					(size 1.27 1.27)
				)
			)
		)
		(property "Value" "4K7R2J-2-GP"
			(at 0.064008 -3.993896 270)
			(unlocked yes)
			(layer "F.Fab")
			(hide yes)
			(effects
				(font
					(size 1.016 1.016)
					(thickness 0.1524)
				)
			)
		)
		(property "Device Type" "R402H16"
			(at 0.064008 -5.517896 270)
			(unlocked yes)
			(layer "F.Fab")
			(hide yes)
			(effects
				(font
					(size 1.016 1.016)
					(thickness 0.1524)
				)
			)
		)
		(duplicate_pad_numbers_are_jumpers no)
		(fp_line
			(start -0.508 -0.9398)
			(end -0.508 0.9398)
			(stroke
				(width 0.1524)
				(type default)
			)
			(layer "F.SilkS")
		)
		(fp_line
			(start 0.508 -0.9398)
			(end -0.508 -0.9398)
			(stroke
				(width 0.1524)
				(type default)
			)
			(layer "F.SilkS")
		)
		(fp_rect
			(start -0.508 0.9398)
			(end 0.508 -0.9398)
			(stroke
				(width 0)
				(type default)
			)
			(fill no)
			(layer "F.CrtYd")
		)
		(fp_rect
			(start -0.508 0.9398)
			(end 0.508 -0.9398)
			(stroke
				(width 0)
				(type default)
			)
			(fill no)
			(layer "F.Fab")
		)
		(pad "1" smd custom
			(at 0 -0.4445 270)
			(size 0.1397 0.1397)
			(layers "F.Cu" "F.Mask" "F.Paste")
			(net "DRIVE_A_19_ACT")
			(options
				(clearance outline)
				(anchor circle)
			)
			(primitives
				(gr_poly
					(pts
						(arc
							(start -0.1778 -0.2794)
							(mid -0.249642 -0.249642)
							(end -0.2794 -0.1778)
						)
						(arc
							(start -0.2794 0.1778)
							(mid -0.249642 0.249642)
							(end -0.1778 0.2794)
						)
						(arc
							(start 0.1778 0.2794)
							(mid 0.249642 0.249642)
							(end 0.2794 0.1778)
						)
						(arc
							(start 0.2794 -0.1778)
							(mid 0.249642 -0.249642)
							(end 0.1778 -0.2794)
						)
					)
					(width 0)
					(fill yes)
				)
			)
		)
		(pad "2" smd custom
			(at 0 0.4445 270)
			(size 0.1397 0.1397)
			(layers "F.Cu" "F.Mask" "F.Paste")
			(net "GND")
			(options
				(clearance outline)
				(anchor circle)
			)
			(primitives
				(gr_poly
					(pts
						(arc
							(start -0.1778 -0.2794)
							(mid -0.249642 -0.249642)
							(end -0.2794 -0.1778)
						)
						(arc
							(start -0.2794 0.1778)
							(mid -0.249642 0.249642)
							(end -0.1778 0.2794)
						)
						(arc
							(start 0.1778 0.2794)
							(mid 0.249642 0.249642)
							(end 0.2794 0.1778)
						)
						(arc
							(start 0.2794 -0.1778)
							(mid 0.249642 -0.249642)
							(end 0.1778 -0.2794)
						)
					)
					(width 0)
					(fill yes)
				)
			)
		)
	)
	(footprint ""
		(layer "F.Cu")
		(at 332.74 -278.554942 -90)
		(property "Reference" "R275"
			(at 0 0 270)
			(layer "F.SilkS")
			(hide yes)
			(effects
				(font
					(size 1.27 1.27)
				)
			)
		)
		(property "Value" "4K7R2J-2-GP"
			(at 0.064008 -3.993896 270)
			(unlocked yes)
			(layer "F.Fab")
			(hide yes)
			(effects
				(font
					(size 1.016 1.016)
					(thickness 0.1524)
				)
			)
		)
		(property "Device Type" "R402H16"
			(at 0.064008 -5.517896 270)
			(unlocked yes)
			(layer "F.Fab")
			(hide yes)
			(effects
				(font
					(size 1.016 1.016)
					(thickness 0.1524)
				)
			)
		)
		(duplicate_pad_numbers_are_jumpers no)
		(fp_line
			(start -0.508 -0.9398)
			(end -0.508 0.9398)
			(stroke
				(width 0.1524)
				(type default)
			)
			(layer "F.SilkS")
		)
		(fp_line
			(start 0.508 -0.9398)
			(end -0.508 -0.9398)
			(stroke
				(width 0.1524)
				(type default)
			)
			(layer "F.SilkS")
		)
		(fp_rect
			(start -0.508 0.9398)
			(end 0.508 -0.9398)
			(stroke
				(width 0)
				(type default)
			)
			(fill no)
			(layer "F.CrtYd")
		)
		(fp_rect
			(start -0.508 0.9398)
			(end 0.508 -0.9398)
			(stroke
				(width 0)
				(type default)
			)
			(fill no)
			(layer "F.Fab")
		)
		(pad "1" smd custom
			(at 0 -0.4445 270)
			(size 0.1397 0.1397)
			(layers "F.Cu" "F.Mask" "F.Paste")
			(net "P12V_A")
			(options
				(clearance outline)
				(anchor circle)
			)
			(primitives
				(gr_poly
					(pts
						(arc
							(start -0.1778 -0.2794)
							(mid -0.249642 -0.249642)
							(end -0.2794 -0.1778)
						)
						(arc
							(start -0.2794 0.1778)
							(mid -0.249642 0.249642)
							(end -0.1778 0.2794)
						)
						(arc
							(start 0.1778 0.2794)
							(mid 0.249642 0.249642)
							(end 0.2794 0.1778)
						)
						(arc
							(start 0.2794 -0.1778)
							(mid 0.249642 -0.249642)
							(end 0.1778 -0.2794)
						)
					)
					(width 0)
					(fill yes)
				)
			)
		)
		(pad "2" smd custom
			(at 0 0.4445 270)
			(size 0.1397 0.1397)
			(layers "F.Cu" "F.Mask" "F.Paste")
			(net "SW_HDD_P6")
			(options
				(clearance outline)
				(anchor circle)
			)
			(primitives
				(gr_poly
					(pts
						(arc
							(start -0.1778 -0.2794)
							(mid -0.249642 -0.249642)
							(end -0.2794 -0.1778)
						)
						(arc
							(start -0.2794 0.1778)
							(mid -0.249642 0.249642)
							(end -0.1778 0.2794)
						)
						(arc
							(start 0.1778 0.2794)
							(mid 0.249642 0.249642)
							(end 0.2794 0.1778)
						)
						(arc
							(start 0.2794 -0.1778)
							(mid 0.249642 -0.249642)
							(end 0.1778 -0.2794)
						)
					)
					(width 0)
					(fill yes)
				)
			)
		)
	)
	(footprint ""
		(layer "F.Cu")
		(at 48.98517 -147.503642 -90)
		(property "Reference" "R1233"
			(at 0 0 270)
			(layer "F.SilkS")
			(hide yes)
			(effects
				(font
					(size 1.27 1.27)
				)
			)
		)
		(property "Value" "15KR2F-GP"
			(at 0.064008 -3.993896 270)
			(unlocked yes)
			(layer "F.Fab")
			(hide yes)
			(effects
				(font
					(size 1.016 1.016)
					(thickness 0.1524)
				)
			)
		)
		(property "Device Type" "R402H16"
			(at 0.064008 -5.517896 270)
			(unlocked yes)
			(layer "F.Fab")
			(hide yes)
			(effects
				(font
					(size 1.016 1.016)
					(thickness 0.1524)
				)
			)
		)
		(duplicate_pad_numbers_are_jumpers no)
		(fp_line
			(start -0.508 -0.9398)
			(end -0.508 0.9398)
			(stroke
				(width 0.1524)
				(type default)
			)
			(layer "F.SilkS")
		)
		(fp_line
			(start 0.508 -0.9398)
			(end -0.508 -0.9398)
			(stroke
				(width 0.1524)
				(type default)
			)
			(layer "F.SilkS")
		)
		(fp_rect
			(start -0.508 0.9398)
			(end 0.508 -0.9398)
			(stroke
				(width 0)
				(type default)
			)
			(fill no)
			(layer "F.CrtYd")
		)
		(fp_rect
			(start -0.508 0.9398)
			(end 0.508 -0.9398)
			(stroke
				(width 0)
				(type default)
			)
			(fill no)
			(layer "F.Fab")
		)
		(pad "1" smd custom
			(at 0 -0.4445 270)
			(size 0.1397 0.1397)
			(layers "F.Cu" "F.Mask" "F.Paste")
			(net "P5V_A_2_PGOOD")
			(options
				(clearance outline)
				(anchor circle)
			)
			(primitives
				(gr_poly
					(pts
						(arc
							(start -0.1778 -0.2794)
							(mid -0.249642 -0.249642)
							(end -0.2794 -0.1778)
						)
						(arc
							(start -0.2794 0.1778)
							(mid -0.249642 0.249642)
							(end -0.1778 0.2794)
						)
						(arc
							(start 0.1778 0.2794)
							(mid 0.249642 0.249642)
							(end 0.2794 0.1778)
						)
						(arc
							(start 0.2794 -0.1778)
							(mid 0.249642 -0.249642)
							(end 0.1778 -0.2794)
						)
					)
					(width 0)
					(fill yes)
				)
			)
		)
		(pad "2" smd custom
			(at 0 0.4445 270)
			(size 0.1397 0.1397)
			(layers "F.Cu" "F.Mask" "F.Paste")
			(net "GND")
			(options
				(clearance outline)
				(anchor circle)
			)
			(primitives
				(gr_poly
					(pts
						(arc
							(start -0.1778 -0.2794)
							(mid -0.249642 -0.249642)
							(end -0.2794 -0.1778)
						)
						(arc
							(start -0.2794 0.1778)
							(mid -0.249642 0.249642)
							(end -0.1778 0.2794)
						)
						(arc
							(start 0.1778 0.2794)
							(mid 0.249642 0.249642)
							(end 0.2794 0.1778)
						)
						(arc
							(start 0.2794 -0.1778)
							(mid 0.249642 -0.249642)
							(end 0.1778 -0.2794)
						)
					)
					(width 0)
					(fill yes)
				)
			)
		)
	)
	(footprint ""
		(layer "F.Cu")
		(at 224.409 -10.541 90)
		(property "Reference" "R1004"
			(at 0 0 90)
			(layer "F.SilkS")
			(hide yes)
			(effects
				(font
					(size 1.27 1.27)
				)
			)
		)
		(property "Value" "100KR2F-L1-GP"
			(at 0.064008 -3.993896 90)
			(unlocked yes)
			(layer "F.Fab")
			(hide yes)
			(effects
				(font
					(size 1.016 1.016)
					(thickness 0.1524)
				)
			)
		)
		(property "Device Type" "R402H16"
			(at 0.064008 -5.517896 90)
			(unlocked yes)
			(layer "F.Fab")
			(hide yes)
			(effects
				(font
					(size 1.016 1.016)
					(thickness 0.1524)
				)
			)
		)
		(duplicate_pad_numbers_are_jumpers no)
		(fp_line
			(start 0.508 -0.9398)
			(end -0.508 -0.9398)
			(stroke
				(width 0.1524)
				(type default)
			)
			(layer "F.SilkS")
		)
		(fp_line
			(start -0.508 -0.9398)
			(end -0.508 0.9398)
			(stroke
				(width 0.1524)
				(type default)
			)
			(layer "F.SilkS")
		)
		(fp_rect
			(start -0.508 0.9398)
			(end 0.508 -0.9398)
			(stroke
				(width 0)
				(type default)
			)
			(fill no)
			(layer "F.CrtYd")
		)
		(fp_rect
			(start -0.508 0.9398)
			(end 0.508 -0.9398)
			(stroke
				(width 0)
				(type default)
			)
			(fill no)
			(layer "F.Fab")
		)
		(pad "1" smd custom
			(at 0 -0.4445 90)
			(size 0.1397 0.1397)
			(layers "F.Cu" "F.Mask" "F.Paste")
			(net "P3V3_STBY_A")
			(options
				(clearance outline)
				(anchor circle)
			)
			(primitives
				(gr_poly
					(pts
						(arc
							(start -0.1778 -0.2794)
							(mid -0.249642 -0.249642)
							(end -0.2794 -0.1778)
						)
						(arc
							(start -0.2794 0.1778)
							(mid -0.249642 0.249642)
							(end -0.1778 0.2794)
						)
						(arc
							(start 0.1778 0.2794)
							(mid 0.249642 0.249642)
							(end 0.2794 0.1778)
						)
						(arc
							(start 0.2794 -0.1778)
							(mid 0.249642 -0.249642)
							(end 0.1778 -0.2794)
						)
					)
					(width 0)
					(fill yes)
				)
			)
		)
		(pad "2" smd custom
			(at 0 0.4445 90)
			(size 0.1397 0.1397)
			(layers "F.Cu" "F.Mask" "F.Paste")
			(net "COMP_A_SEC_INS_N")
			(options
				(clearance outline)
				(anchor circle)
			)
			(primitives
				(gr_poly
					(pts
						(arc
							(start -0.1778 -0.2794)
							(mid -0.249642 -0.249642)
							(end -0.2794 -0.1778)
						)
						(arc
							(start -0.2794 0.1778)
							(mid -0.249642 0.249642)
							(end -0.1778 0.2794)
						)
						(arc
							(start 0.1778 0.2794)
							(mid 0.249642 0.249642)
							(end 0.2794 0.1778)
						)
						(arc
							(start 0.2794 -0.1778)
							(mid 0.249642 -0.249642)
							(end 0.1778 -0.2794)
						)
					)
					(width 0)
					(fill yes)
				)
			)
		)
	)
)
